(kicad_pcb
	(version 20260206)
	(generator "pcbnew")
	(generator_version "10.0")
	(general
		(thickness 1.6)
		(legacy_teardrops no)
	)
	(paper "A4")
	(title_block
		(title "04192023_DAF0TMB3IC0_F0TG_MB_C_brd_V02_OCP.brd")
		(comment 1 "Grand Teton / footprints 72-77 of 8354")
	)
	(layers
		(0 "F.Cu" signal "TOP")
		(4 "In1.Cu" signal "GND")
		(6 "In2.Cu" signal "IN1")
		(8 "In3.Cu" signal "GND1")
		(10 "In4.Cu" signal "IN2")
		(12 "In5.Cu" signal "GND2")
		(14 "In6.Cu" signal "IN3")
		(16 "In7.Cu" signal "GND3")
		(18 "In8.Cu" signal "VCC")
		(20 "In9.Cu" signal "VCC1")
		(22 "In10.Cu" signal "GND4")
		(24 "In11.Cu" signal "IN4")
		(26 "In12.Cu" signal "GND5")
		(28 "In13.Cu" signal "IN5")
		(30 "In14.Cu" signal "GND6")
		(32 "In15.Cu" signal "IN6")
		(34 "In16.Cu" signal "GND7")
		(2 "B.Cu" signal "BOTTOM")
		(9 "F.Adhes" user "F.Adhesive")
		(11 "B.Adhes" user "B.Adhesive")
		(13 "F.Paste" user "Package Geometry/Pastemask Top")
		(15 "B.Paste" user "Package Geometry/Pastemask Bottom")
		(5 "F.SilkS" user "Ref Des/Silkscreen Top")
		(7 "B.SilkS" user "Ref Des/Silkscreen Bottom")
		(1 "F.Mask" user "Board Geometry/Soldermask Top")
		(3 "B.Mask" user "Board Geometry/Soldermask Bottom")
		(17 "Dwgs.User" user "User.Drawings")
		(19 "Cmts.User" user "User.Comments")
		(21 "Eco1.User" user "User.Eco1")
		(23 "Eco2.User" user "User.Eco2")
		(25 "Edge.Cuts" user "Board Geometry/Outline")
		(27 "Margin" user)
		(31 "F.CrtYd" user "Package Geometry/Place Bound Top")
		(29 "B.CrtYd" user "Package Geometry/Place Bound Bottom")
		(35 "F.Fab" user "Ref Des/Assembly Top")
		(33 "B.Fab" user "Ref Des/Assembly Bottom")
	)
	(footprint ""
		(layer "F.Cu")
		(at 320.131694 -339.647022 -90)
		(property "Reference" "PC122"
			(at 0 0 270)
			(layer "F.SilkS")
			(hide yes)
			(effects
				(font
					(size 1.27 1.27)
				)
			)
		)
		(property "Value" ""
			(at 0 0 270)
			(layer "F.Fab")
			(effects
				(font
					(size 1.27 1.27)
				)
			)
		)
		(duplicate_pad_numbers_are_jumpers no)
		(fp_line
			(start -0.7874 0.4064)
			(end -0.7874 -0.4064)
			(stroke
				(width 0.1524)
				(type default)
			)
			(layer "F.SilkS")
		)
		(fp_line
			(start 0.7874 0.4064)
			(end -0.7874 0.4064)
			(stroke
				(width 0.1524)
				(type default)
			)
			(layer "F.SilkS")
		)
		(fp_line
			(start -0.7874 -0.4064)
			(end 0.7874 -0.4064)
			(stroke
				(width 0.1524)
				(type default)
			)
			(layer "F.SilkS")
		)
		(fp_line
			(start 0.7874 -0.4064)
			(end 0.7874 0.4064)
			(stroke
				(width 0.1524)
				(type default)
			)
			(layer "F.SilkS")
		)
		(fp_line
			(start -0.67945 0.3048)
			(end -0.67945 -0.305054)
			(stroke
				(width 0.1)
				(type default)
			)
			(layer "F.Fab")
		)
		(fp_line
			(start -0.12065 0.3048)
			(end -0.67945 0.3048)
			(stroke
				(width 0.1)
				(type default)
			)
			(layer "F.Fab")
		)
		(fp_line
			(start 0.120396 0.3048)
			(end 0.120396 0.2794)
			(stroke
				(width 0.1)
				(type default)
			)
			(layer "F.Fab")
		)
		(fp_line
			(start 0.67945 0.3048)
			(end 0.120396 0.3048)
			(stroke
				(width 0.1)
				(type default)
			)
			(layer "F.Fab")
		)
		(fp_line
			(start -0.12065 0.2794)
			(end -0.12065 0.3048)
			(stroke
				(width 0.1)
				(type default)
			)
			(layer "F.Fab")
		)
		(fp_line
			(start 0.120396 0.2794)
			(end -0.12065 0.2794)
			(stroke
				(width 0.1)
				(type default)
			)
			(layer "F.Fab")
		)
		(fp_line
			(start -0.12065 -0.2794)
			(end 0.12065 -0.2794)
			(stroke
				(width 0.1)
				(type default)
			)
			(layer "F.Fab")
		)
		(fp_line
			(start 0.12065 -0.2794)
			(end 0.12065 -0.3048)
			(stroke
				(width 0.1)
				(type default)
			)
			(layer "F.Fab")
		)
		(fp_line
			(start 0.12065 -0.3048)
			(end 0.67945 -0.3048)
			(stroke
				(width 0.1)
				(type default)
			)
			(layer "F.Fab")
		)
		(fp_line
			(start 0.67945 -0.3048)
			(end 0.67945 0.3048)
			(stroke
				(width 0.1)
				(type default)
			)
			(layer "F.Fab")
		)
		(fp_line
			(start -0.67945 -0.305054)
			(end -0.12065 -0.305054)
			(stroke
				(width 0.1)
				(type default)
			)
			(layer "F.Fab")
		)
		(fp_line
			(start -0.12065 -0.305054)
			(end -0.12065 -0.2794)
			(stroke
				(width 0.1)
				(type default)
			)
			(layer "F.Fab")
		)
		(pad "1" smd circle
			(at -0.40005 0 270)
			(size 0 0)
			(layers "F.Cu" "F.Mask" "F.Paste")
			(net "SW_PVDDCR_CPU1_P0_BOOT3_R")
		)
		(pad "2" smd circle
			(at 0.40005 0 270)
			(size 0 0)
			(layers "F.Cu" "F.Mask" "F.Paste")
			(net "SW_PVDDCR_CPU1_P0_BOOTR3")
		)
	)
	(footprint ""
		(layer "F.Cu")
		(at 100.920296 -425.82973 -90)
		(property "Reference" "R4186"
			(at 0 0 270)
			(layer "F.SilkS")
			(hide yes)
			(effects
				(font
					(size 1.27 1.27)
				)
			)
		)
		(property "Value" ""
			(at 0 0 270)
			(layer "F.Fab")
			(effects
				(font
					(size 1.27 1.27)
				)
			)
		)
		(duplicate_pad_numbers_are_jumpers no)
		(fp_line
			(start -0.7874 0.4064)
			(end -0.7874 -0.4064)
			(stroke
				(width 0.1524)
				(type default)
			)
			(layer "F.SilkS")
		)
		(fp_line
			(start 0.7874 0.4064)
			(end -0.7874 0.4064)
			(stroke
				(width 0.1524)
				(type default)
			)
			(layer "F.SilkS")
		)
		(fp_line
			(start -0.7874 -0.4064)
			(end 0.7874 -0.4064)
			(stroke
				(width 0.1524)
				(type default)
			)
			(layer "F.SilkS")
		)
		(fp_line
			(start 0.7874 -0.4064)
			(end 0.7874 0.4064)
			(stroke
				(width 0.1524)
				(type default)
			)
			(layer "F.SilkS")
		)
		(fp_line
			(start -0.67945 0.3048)
			(end -0.67945 -0.305054)
			(stroke
				(width 0.1)
				(type default)
			)
			(layer "F.Fab")
		)
		(fp_line
			(start -0.12065 0.3048)
			(end -0.67945 0.3048)
			(stroke
				(width 0.1)
				(type default)
			)
			(layer "F.Fab")
		)
		(fp_line
			(start 0.120396 0.3048)
			(end 0.120396 0.2794)
			(stroke
				(width 0.1)
				(type default)
			)
			(layer "F.Fab")
		)
		(fp_line
			(start 0.67945 0.3048)
			(end 0.120396 0.3048)
			(stroke
				(width 0.1)
				(type default)
			)
			(layer "F.Fab")
		)
		(fp_line
			(start -0.12065 0.2794)
			(end -0.12065 0.3048)
			(stroke
				(width 0.1)
				(type default)
			)
			(layer "F.Fab")
		)
		(fp_line
			(start 0.120396 0.2794)
			(end -0.12065 0.2794)
			(stroke
				(width 0.1)
				(type default)
			)
			(layer "F.Fab")
		)
		(fp_line
			(start -0.12065 -0.2794)
			(end 0.12065 -0.2794)
			(stroke
				(width 0.1)
				(type default)
			)
			(layer "F.Fab")
		)
		(fp_line
			(start 0.12065 -0.2794)
			(end 0.12065 -0.3048)
			(stroke
				(width 0.1)
				(type default)
			)
			(layer "F.Fab")
		)
		(fp_line
			(start 0.12065 -0.3048)
			(end 0.67945 -0.3048)
			(stroke
				(width 0.1)
				(type default)
			)
			(layer "F.Fab")
		)
		(fp_line
			(start 0.67945 -0.3048)
			(end 0.67945 0.3048)
			(stroke
				(width 0.1)
				(type default)
			)
			(layer "F.Fab")
		)
		(fp_line
			(start -0.67945 -0.305054)
			(end -0.12065 -0.305054)
			(stroke
				(width 0.1)
				(type default)
			)
			(layer "F.Fab")
		)
		(fp_line
			(start -0.12065 -0.305054)
			(end -0.12065 -0.2794)
			(stroke
				(width 0.1)
				(type default)
			)
			(layer "F.Fab")
		)
		(pad "1" smd circle
			(at -0.40005 0 270)
			(size 0 0)
			(layers "F.Cu" "F.Mask" "F.Paste")
			(net "P3V3_AUX")
		)
		(pad "2" smd circle
			(at 0.40005 0 270)
			(size 0 0)
			(layers "F.Cu" "F.Mask" "F.Paste")
			(net "U272_2_ADD2")
		)
	)
	(footprint ""
		(layer "F.Cu")
		(at 110.527084 -261.748016 -90)
		(property "Reference" "C2504"
			(at 0 0 270)
			(layer "F.SilkS")
			(hide yes)
			(effects
				(font
					(size 1.27 1.27)
				)
			)
		)
		(property "Value" ""
			(at 0 0 270)
			(layer "F.Fab")
			(effects
				(font
					(size 1.27 1.27)
				)
			)
		)
		(duplicate_pad_numbers_are_jumpers no)
		(fp_line
			(start -0.7874 0.4064)
			(end -0.7874 -0.4064)
			(stroke
				(width 0.1524)
				(type default)
			)
			(layer "F.SilkS")
		)
		(fp_line
			(start 0.7874 0.4064)
			(end -0.7874 0.4064)
			(stroke
				(width 0.1524)
				(type default)
			)
			(layer "F.SilkS")
		)
		(fp_line
			(start -0.7874 -0.4064)
			(end 0.7874 -0.4064)
			(stroke
				(width 0.1524)
				(type default)
			)
			(layer "F.SilkS")
		)
		(fp_line
			(start 0.7874 -0.4064)
			(end 0.7874 0.4064)
			(stroke
				(width 0.1524)
				(type default)
			)
			(layer "F.SilkS")
		)
		(fp_line
			(start -0.67945 0.3048)
			(end -0.67945 -0.305054)
			(stroke
				(width 0.1)
				(type default)
			)
			(layer "F.Fab")
		)
		(fp_line
			(start -0.12065 0.3048)
			(end -0.67945 0.3048)
			(stroke
				(width 0.1)
				(type default)
			)
			(layer "F.Fab")
		)
		(fp_line
			(start 0.120396 0.3048)
			(end 0.120396 0.2794)
			(stroke
				(width 0.1)
				(type default)
			)
			(layer "F.Fab")
		)
		(fp_line
			(start 0.67945 0.3048)
			(end 0.120396 0.3048)
			(stroke
				(width 0.1)
				(type default)
			)
			(layer "F.Fab")
		)
		(fp_line
			(start -0.12065 0.2794)
			(end -0.12065 0.3048)
			(stroke
				(width 0.1)
				(type default)
			)
			(layer "F.Fab")
		)
		(fp_line
			(start 0.120396 0.2794)
			(end -0.12065 0.2794)
			(stroke
				(width 0.1)
				(type default)
			)
			(layer "F.Fab")
		)
		(fp_line
			(start -0.12065 -0.2794)
			(end 0.12065 -0.2794)
			(stroke
				(width 0.1)
				(type default)
			)
			(layer "F.Fab")
		)
		(fp_line
			(start 0.12065 -0.2794)
			(end 0.12065 -0.3048)
			(stroke
				(width 0.1)
				(type default)
			)
			(layer "F.Fab")
		)
		(fp_line
			(start 0.12065 -0.3048)
			(end 0.67945 -0.3048)
			(stroke
				(width 0.1)
				(type default)
			)
			(layer "F.Fab")
		)
		(fp_line
			(start 0.67945 -0.3048)
			(end 0.67945 0.3048)
			(stroke
				(width 0.1)
				(type default)
			)
			(layer "F.Fab")
		)
		(fp_line
			(start -0.67945 -0.305054)
			(end -0.12065 -0.305054)
			(stroke
				(width 0.1)
				(type default)
			)
			(layer "F.Fab")
		)
		(fp_line
			(start -0.12065 -0.305054)
			(end -0.12065 -0.2794)
			(stroke
				(width 0.1)
				(type default)
			)
			(layer "F.Fab")
		)
		(pad "1" smd circle
			(at -0.40005 0 270)
			(size 0 0)
			(layers "F.Cu" "F.Mask" "F.Paste")
			(net "PVDD11_S3_P1")
		)
		(pad "2" smd circle
			(at 0.40005 0 270)
			(size 0 0)
			(layers "F.Cu" "F.Mask" "F.Paste")
			(net "GND")
		)
	)
	(footprint ""
		(layer "F.Cu")
		(at 403.013418 -135.58139 180)
		(property "Reference" "Q50"
			(at 0.719074 2.0066 0)
			(unlocked yes)
			(layer "F.SilkS")
			(effects
				(font
					(size 0.7874 0.5842)
					(thickness 0.1524)
				)
				(justify left)
			)
		)
		(property "Value" ""
			(at 0 0 180)
			(layer "F.Fab")
			(effects
				(font
					(size 1.27 1.27)
				)
			)
		)
		(duplicate_pad_numbers_are_jumpers no)
		(fp_line
			(start 1.332738 1.100074)
			(end -1.332738 1.100074)
			(stroke
				(width 0.1524)
				(type default)
			)
			(layer "F.SilkS")
		)
		(fp_line
			(start 1.332738 -1.100074)
			(end 1.332738 1.100074)
			(stroke
				(width 0.1524)
				(type default)
			)
			(layer "F.SilkS")
		)
		(fp_line
			(start 0.4826 -1.100074)
			(end 1.332738 -1.100074)
			(stroke
				(width 0.1524)
				(type default)
			)
			(layer "F.SilkS")
		)
		(fp_line
			(start 0 -0.541274)
			(end 0.4826 -1.100074)
			(stroke
				(width 0.1524)
				(type default)
			)
			(layer "F.SilkS")
		)
		(fp_line
			(start -0.4826 -1.100074)
			(end 0 -0.541274)
			(stroke
				(width 0.1524)
				(type default)
			)
			(layer "F.SilkS")
		)
		(fp_line
			(start -1.332738 1.100074)
			(end -1.332738 -1.100074)
			(stroke
				(width 0.1524)
				(type default)
			)
			(layer "F.SilkS")
		)
		(fp_line
			(start -1.332738 -1.100074)
			(end -0.4826 -1.100074)
			(stroke
				(width 0.1524)
				(type default)
			)
			(layer "F.SilkS")
		)
		(fp_poly
			(pts
				(xy -1.823212 -0.905764) (xy -2.525268 -0.554736) (xy -2.525268 -1.256792)
			)
			(stroke
				(width 0)
				(type default)
			)
			(fill yes)
			(layer "F.SilkS")
		)
		(fp_line
			(start 0.674878 1.100074)
			(end -0.674878 1.100074)
			(stroke
				(width 0.1)
				(type default)
			)
			(layer "F.Fab")
		)
		(fp_line
			(start 0.674878 -1.100074)
			(end 0.674878 1.100074)
			(stroke
				(width 0.1)
				(type default)
			)
			(layer "F.Fab")
		)
		(fp_line
			(start -0.674878 1.100074)
			(end -0.674878 -1.100074)
			(stroke
				(width 0.1)
				(type default)
			)
			(layer "F.Fab")
		)
		(fp_line
			(start -0.674878 -1.100074)
			(end 0.674878 -1.100074)
			(stroke
				(width 0.1)
				(type default)
			)
			(layer "F.Fab")
		)
		(fp_poly
			(pts
				(xy -2.2352 -0.298958) (xy -2.2352 -1.001014) (xy -1.533144 -0.649986)
			)
			(stroke
				(width 0)
				(type default)
			)
			(fill yes)
			(layer "F.Fab")
		)
		(pad "1" smd rect
			(at -0.94996 -0.649986 270)
			(size 0.4318 0.508)
			(layers "F.Cu" "F.Mask" "F.Paste")
			(net "GND")
		)
		(pad "2" smd rect
			(at -0.94996 0 270)
			(size 0.4318 0.508)
			(layers "F.Cu" "F.Mask" "F.Paste")
			(net "PWRGD_P5V_AUX")
		)
		(pad "3" smd rect
			(at -0.94996 0.649986 270)
			(size 0.4318 0.508)
			(layers "F.Cu" "F.Mask" "F.Paste")
			(net "PWRGD_P5V_AUX_R2")
		)
		(pad "4" smd rect
			(at 0.94996 0.649986 270)
			(size 0.4318 0.508)
			(layers "F.Cu" "F.Mask" "F.Paste")
			(net "GND")
		)
		(pad "5" smd rect
			(at 0.94996 0 270)
			(size 0.4318 0.508)
			(layers "F.Cu" "F.Mask" "F.Paste")
			(net "PWRGD_P5V_AUX_R1")
		)
		(pad "6" smd rect
			(at 0.94996 -0.649986 270)
			(size 0.4318 0.508)
			(layers "F.Cu" "F.Mask" "F.Paste")
			(net "PWRGD_P5V_AUX_R1")
		)
	)
	(footprint ""
		(layer "F.Cu")
		(at 332.807564 -135.156702 180)
		(property "Reference" "PC254"
			(at 0 0 180)
			(layer "F.SilkS")
			(hide yes)
			(effects
				(font
					(size 1.27 1.27)
				)
			)
		)
		(property "Value" ""
			(at 0 0 180)
			(layer "F.Fab")
			(effects
				(font
					(size 1.27 1.27)
				)
			)
		)
		(duplicate_pad_numbers_are_jumpers no)
		(fp_line
			(start 1.524 0.762)
			(end -1.524 0.762)
			(stroke
				(width 0.1524)
				(type default)
			)
			(layer "F.SilkS")
		)
		(fp_line
			(start 1.524 -0.762)
			(end 1.524 0.762)
			(stroke
				(width 0.1524)
				(type default)
			)
			(layer "F.SilkS")
		)
		(fp_line
			(start -1.524 0.762)
			(end -1.524 -0.762)
			(stroke
				(width 0.1524)
				(type default)
			)
			(layer "F.SilkS")
		)
		(fp_line
			(start -1.524 -0.762)
			(end 1.524 -0.762)
			(stroke
				(width 0.1524)
				(type default)
			)
			(layer "F.SilkS")
		)
		(fp_line
			(start 1.1049 0.724916)
			(end 1.1049 -0.724916)
			(stroke
				(width 0.1)
				(type default)
			)
			(layer "F.Fab")
		)
		(fp_line
			(start 1.1049 -0.724916)
			(end -1.1049 -0.724916)
			(stroke
				(width 0.1)
				(type default)
			)
			(layer "F.Fab")
		)
		(fp_line
			(start -1.1049 0.724916)
			(end 1.1049 0.724916)
			(stroke
				(width 0.1)
				(type default)
			)
			(layer "F.Fab")
		)
		(fp_line
			(start -1.1049 -0.724916)
			(end -1.1049 0.724916)
			(stroke
				(width 0.1)
				(type default)
			)
			(layer "F.Fab")
		)
		(pad "1" smd rect
			(at -0.889 0)
			(size 1.016 1.27)
			(layers "F.Cu" "F.Mask" "F.Paste")
			(net "SW_P12V_AUX_PVDD18_S5_P0_FLT")
		)
		(pad "2" smd rect
			(at 0.889 0)
			(size 1.016 1.27)
			(layers "F.Cu" "F.Mask" "F.Paste")
			(net "GND")
		)
	)
	(footprint ""
		(layer "F.Cu")
		(at 362.528104 -173.119542 90)
		(property "Reference" "PC489"
			(at 0 0 90)
			(layer "F.SilkS")
			(hide yes)
			(effects
				(font
					(size 1.27 1.27)
				)
			)
		)
		(property "Value" ""
			(at 0 0 90)
			(layer "F.Fab")
			(effects
				(font
					(size 1.27 1.27)
				)
			)
		)
		(duplicate_pad_numbers_are_jumpers no)
		(fp_line
			(start 0.7874 -0.4064)
			(end 0.7874 0.4064)
			(stroke
				(width 0.1524)
				(type default)
			)
			(layer "F.SilkS")
		)
		(fp_line
			(start -0.7874 -0.4064)
			(end 0.7874 -0.4064)
			(stroke
				(width 0.1524)
				(type default)
			)
			(layer "F.SilkS")
		)
		(fp_line
			(start 0.7874 0.4064)
			(end -0.7874 0.4064)
			(stroke
				(width 0.1524)
				(type default)
			)
			(layer "F.SilkS")
		)
		(fp_line
			(start -0.7874 0.4064)
			(end -0.7874 -0.4064)
			(stroke
				(width 0.1524)
				(type default)
			)
			(layer "F.SilkS")
		)
		(fp_line
			(start -0.12065 -0.305054)
			(end -0.12065 -0.2794)
			(stroke
				(width 0.1)
				(type default)
			)
			(layer "F.Fab")
		)
		(fp_line
			(start -0.67945 -0.305054)
			(end -0.12065 -0.305054)
			(stroke
				(width 0.1)
				(type default)
			)
			(layer "F.Fab")
		)
		(fp_line
			(start 0.67945 -0.3048)
			(end 0.67945 0.3048)
			(stroke
				(width 0.1)
				(type default)
			)
			(layer "F.Fab")
		)
		(fp_line
			(start 0.12065 -0.3048)
			(end 0.67945 -0.3048)
			(stroke
				(width 0.1)
				(type default)
			)
			(layer "F.Fab")
		)
		(fp_line
			(start 0.12065 -0.2794)
			(end 0.12065 -0.3048)
			(stroke
				(width 0.1)
				(type default)
			)
			(layer "F.Fab")
		)
		(fp_line
			(start -0.12065 -0.2794)
			(end 0.12065 -0.2794)
			(stroke
				(width 0.1)
				(type default)
			)
			(layer "F.Fab")
		)
		(fp_line
			(start 0.120396 0.2794)
			(end -0.12065 0.2794)
			(stroke
				(width 0.1)
				(type default)
			)
			(layer "F.Fab")
		)
		(fp_line
			(start -0.12065 0.2794)
			(end -0.12065 0.3048)
			(stroke
				(width 0.1)
				(type default)
			)
			(layer "F.Fab")
		)
		(fp_line
			(start 0.67945 0.3048)
			(end 0.120396 0.3048)
			(stroke
				(width 0.1)
				(type default)
			)
			(layer "F.Fab")
		)
		(fp_line
			(start 0.120396 0.3048)
			(end 0.120396 0.2794)
			(stroke
				(width 0.1)
				(type default)
			)
			(layer "F.Fab")
		)
		(fp_line
			(start -0.12065 0.3048)
			(end -0.67945 0.3048)
			(stroke
				(width 0.1)
				(type default)
			)
			(layer "F.Fab")
		)
		(fp_line
			(start -0.67945 0.3048)
			(end -0.67945 -0.305054)
			(stroke
				(width 0.1)
				(type default)
			)
			(layer "F.Fab")
		)
		(pad "1" smd circle
			(at -0.40005 0 90)
			(size 0 0)
			(layers "F.Cu" "F.Mask" "F.Paste")
			(net "SW_PVDDCR_CPU0_P0_BOOT1_RC")
		)
		(pad "2" smd circle
			(at 0.40005 0 90)
			(size 0 0)
			(layers "F.Cu" "F.Mask" "F.Paste")
			(net "SW_PVDDCR_CPU0_P0_PH1")
		)
	)
)
